(kicad_pcb
	(version 20260206)
	(generator "pcbnew")
	(generator_version "10.0")
	(general
		(thickness 1.6)
		(legacy_teardrops no)
	)
	(paper "A4")
	(title_block
		(title "peb — Lightning_PEB_BRD.brd")
		(comment 1 "Lightning (Wiwynn / Facebook NVMe JBOF) / footprints 2123-2130 of 2563")
	)
	(layers
		(0 "F.Cu" signal "TOP")
		(4 "In1.Cu" signal "L2GND")
		(6 "In2.Cu" signal "L3")
		(8 "In3.Cu" signal "L4VCC")
		(10 "In4.Cu" signal "L5VCC")
		(12 "In5.Cu" signal "L6")
		(14 "In6.Cu" signal "L7GND")
		(2 "B.Cu" signal "BOTTOM")
		(9 "F.Adhes" user "F.Adhesive")
		(11 "B.Adhes" user "B.Adhesive")
		(13 "F.Paste" user "Package Geometry/Pastemask Top")
		(15 "B.Paste" user "Package Geometry/Pastemask Bottom")
		(5 "F.SilkS" user "Ref Des/Silkscreen Top")
		(7 "B.SilkS" user "Ref Des/Silkscreen Bottom")
		(1 "F.Mask" user "Board Geometry/Soldermask Top")
		(3 "B.Mask" user "Board Geometry/Soldermask Bottom")
		(17 "Dwgs.User" user "User.Drawings")
		(19 "Cmts.User" user "User.Comments")
		(21 "Eco1.User" user "User.Eco1")
		(23 "Eco2.User" user "User.Eco2")
		(25 "Edge.Cuts" user "Board Geometry/Outline")
		(27 "Margin" user)
		(31 "F.CrtYd" user "Package Geometry/Place Bound Top")
		(29 "B.CrtYd" user "Package Geometry/Place Bound Bottom")
		(35 "F.Fab" user "Ref Des/Assembly Top")
		(33 "B.Fab" user "Ref Des/Assembly Bottom")
	)
	(footprint ""
		(layer "B.Cu")
		(at 235.585 -56.00192 -90)
		(property "Reference" "C521"
			(at 0 0 90)
			(layer "B.SilkS")
			(hide yes)
			(effects
				(font
					(size 1.27 1.27)
				)
				(justify mirror)
			)
		)
		(property "Value" "SCD1U16V1KX-1-GP"
			(at 2.8321 -1.7399 270)
			(unlocked yes)
			(layer "B.Fab")
			(hide yes)
			(effects
				(font
					(size 1.016 1.016)
					(thickness 0.1524)
				)
				(justify mirror)
			)
		)
		(property "Device Type" "C0201H13"
			(at 2.8321 -3.2639 270)
			(unlocked yes)
			(layer "B.Fab")
			(hide yes)
			(effects
				(font
					(size 1.016 1.016)
					(thickness 0.1524)
				)
				(justify mirror)
			)
		)
		(duplicate_pad_numbers_are_jumpers no)
		(fp_rect
			(start 0.2794 0.6477)
			(end -0.2794 -0.6477)
			(stroke
				(width 0)
				(type default)
			)
			(fill no)
			(layer "B.CrtYd")
		)
		(fp_rect
			(start 0.2794 0.6477)
			(end -0.2794 -0.6477)
			(stroke
				(width 0)
				(type default)
			)
			(fill no)
			(layer "B.Fab")
		)
		(pad "1" smd custom
			(at 0 -0.2794 90)
			(size 0.0762 0.0762)
			(layers "B.Cu" "B.Mask" "B.Paste")
			(net "DUT_AVD_TX")
			(options
				(clearance outline)
				(anchor circle)
			)
			(primitives
				(gr_poly
					(pts
						(arc
							(start 0.1524 0.127)
							(mid 0.137521 0.162921)
							(end 0.1016 0.1778)
						)
						(arc
							(start -0.1016 0.1778)
							(mid -0.137521 0.162921)
							(end -0.1524 0.127)
						)
						(arc
							(start -0.1524 -0.127)
							(mid -0.137521 -0.162921)
							(end -0.1016 -0.1778)
						)
						(arc
							(start 0.1016 -0.1778)
							(mid 0.137521 -0.162921)
							(end 0.1524 -0.127)
						)
					)
					(width 0)
					(fill yes)
				)
			)
		)
		(pad "2" smd custom
			(at 0 0.2794 90)
			(size 0.0762 0.0762)
			(layers "B.Cu" "B.Mask" "B.Paste")
			(net "GND")
			(options
				(clearance outline)
				(anchor circle)
			)
			(primitives
				(gr_poly
					(pts
						(arc
							(start 0.1524 0.127)
							(mid 0.137521 0.162921)
							(end 0.1016 0.1778)
						)
						(arc
							(start -0.1016 0.1778)
							(mid -0.137521 0.162921)
							(end -0.1524 0.127)
						)
						(arc
							(start -0.1524 -0.127)
							(mid -0.137521 -0.162921)
							(end -0.1016 -0.1778)
						)
						(arc
							(start 0.1016 -0.1778)
							(mid 0.137521 -0.162921)
							(end 0.1524 -0.127)
						)
					)
					(width 0)
					(fill yes)
				)
			)
		)
	)
	(footprint ""
		(layer "B.Cu")
		(at 252.603 -45.991272 -90)
		(property "Reference" "C612"
			(at 0 0 90)
			(layer "B.SilkS")
			(hide yes)
			(effects
				(font
					(size 1.27 1.27)
				)
				(justify mirror)
			)
		)
		(property "Value" "SCD1U16V1KX-1-GP"
			(at 2.8321 -1.7399 270)
			(unlocked yes)
			(layer "B.Fab")
			(hide yes)
			(effects
				(font
					(size 1.016 1.016)
					(thickness 0.1524)
				)
				(justify mirror)
			)
		)
		(property "Device Type" "C0201H13"
			(at 2.8321 -3.2639 270)
			(unlocked yes)
			(layer "B.Fab")
			(hide yes)
			(effects
				(font
					(size 1.016 1.016)
					(thickness 0.1524)
				)
				(justify mirror)
			)
		)
		(duplicate_pad_numbers_are_jumpers no)
		(fp_rect
			(start 0.2794 0.6477)
			(end -0.2794 -0.6477)
			(stroke
				(width 0)
				(type default)
			)
			(fill no)
			(layer "B.CrtYd")
		)
		(fp_rect
			(start 0.2794 0.6477)
			(end -0.2794 -0.6477)
			(stroke
				(width 0)
				(type default)
			)
			(fill no)
			(layer "B.Fab")
		)
		(pad "1" smd custom
			(at 0 -0.2794 90)
			(size 0.0762 0.0762)
			(layers "B.Cu" "B.Mask" "B.Paste")
			(net "DUT_AVD_PCIE")
			(options
				(clearance outline)
				(anchor circle)
			)
			(primitives
				(gr_poly
					(pts
						(arc
							(start 0.1524 0.127)
							(mid 0.137521 0.162921)
							(end 0.1016 0.1778)
						)
						(arc
							(start -0.1016 0.1778)
							(mid -0.137521 0.162921)
							(end -0.1524 0.127)
						)
						(arc
							(start -0.1524 -0.127)
							(mid -0.137521 -0.162921)
							(end -0.1016 -0.1778)
						)
						(arc
							(start 0.1016 -0.1778)
							(mid 0.137521 -0.162921)
							(end 0.1524 -0.127)
						)
					)
					(width 0)
					(fill yes)
				)
			)
		)
		(pad "2" smd custom
			(at 0 0.2794 90)
			(size 0.0762 0.0762)
			(layers "B.Cu" "B.Mask" "B.Paste")
			(net "GND")
			(options
				(clearance outline)
				(anchor circle)
			)
			(primitives
				(gr_poly
					(pts
						(arc
							(start 0.1524 0.127)
							(mid 0.137521 0.162921)
							(end 0.1016 0.1778)
						)
						(arc
							(start -0.1016 0.1778)
							(mid -0.137521 0.162921)
							(end -0.1524 0.127)
						)
						(arc
							(start -0.1524 -0.127)
							(mid -0.137521 -0.162921)
							(end -0.1016 -0.1778)
						)
						(arc
							(start 0.1016 -0.1778)
							(mid 0.137521 -0.162921)
							(end 0.1524 -0.127)
						)
					)
					(width 0)
					(fill yes)
				)
			)
		)
	)
	(footprint ""
		(layer "B.Cu")
		(at 211.900008 -4.064)
		(property "Reference" "R3709"
			(at 0 0 0)
			(layer "B.SilkS")
			(hide yes)
			(effects
				(font
					(size 1.27 1.27)
				)
				(justify mirror)
			)
		)
		(property "Value" "1KR2F-3-GP"
			(at -0.064008 -3.993896 0)
			(unlocked yes)
			(layer "B.Fab")
			(hide yes)
			(effects
				(font
					(size 1.016 1.016)
					(thickness 0.1524)
				)
				(justify mirror)
			)
		)
		(property "Device Type" "R402H16"
			(at -0.064008 -5.517896 0)
			(unlocked yes)
			(layer "B.Fab")
			(hide yes)
			(effects
				(font
					(size 1.016 1.016)
					(thickness 0.1524)
				)
				(justify mirror)
			)
		)
		(duplicate_pad_numbers_are_jumpers no)
		(fp_line
			(start -0.508 -0.9398)
			(end 0.508 -0.9398)
			(stroke
				(width 0.1524)
				(type default)
			)
			(layer "B.SilkS")
		)
		(fp_line
			(start 0.508 -0.9398)
			(end 0.508 0.9398)
			(stroke
				(width 0.1524)
				(type default)
			)
			(layer "B.SilkS")
		)
		(fp_rect
			(start 0.508 0.9398)
			(end -0.508 -0.9398)
			(stroke
				(width 0)
				(type default)
			)
			(fill no)
			(layer "B.CrtYd")
		)
		(fp_rect
			(start 0.508 0.9398)
			(end -0.508 -0.9398)
			(stroke
				(width 0)
				(type default)
			)
			(fill no)
			(layer "B.Fab")
		)
		(pad "1" smd custom
			(at 0 -0.4445 180)
			(size 0.1397 0.1397)
			(layers "B.Cu" "B.Mask" "B.Paste")
			(net "HOST5_RST_N")
			(options
				(clearance outline)
				(anchor circle)
			)
			(primitives
				(gr_poly
					(pts
						(arc
							(start -0.1778 0.2794)
							(mid -0.249642 0.249642)
							(end -0.2794 0.1778)
						)
						(arc
							(start -0.2794 -0.1778)
							(mid -0.249642 -0.249642)
							(end -0.1778 -0.2794)
						)
						(arc
							(start 0.1778 -0.2794)
							(mid 0.249642 -0.249642)
							(end 0.2794 -0.1778)
						)
						(arc
							(start 0.2794 0.1778)
							(mid 0.249642 0.249642)
							(end 0.1778 0.2794)
						)
					)
					(width 0)
					(fill yes)
				)
			)
		)
		(pad "2" smd custom
			(at 0 0.4445 180)
			(size 0.1397 0.1397)
			(layers "B.Cu" "B.Mask" "B.Paste")
			(net "P3V3_STBY")
			(options
				(clearance outline)
				(anchor circle)
			)
			(primitives
				(gr_poly
					(pts
						(arc
							(start -0.1778 0.2794)
							(mid -0.249642 0.249642)
							(end -0.2794 0.1778)
						)
						(arc
							(start -0.2794 -0.1778)
							(mid -0.249642 -0.249642)
							(end -0.1778 -0.2794)
						)
						(arc
							(start 0.1778 -0.2794)
							(mid 0.249642 -0.249642)
							(end 0.2794 -0.1778)
						)
						(arc
							(start 0.2794 0.1778)
							(mid 0.249642 0.249642)
							(end 0.1778 0.2794)
						)
					)
					(width 0)
					(fill yes)
				)
			)
		)
	)
	(footprint ""
		(layer "B.Cu")
		(at 48.1584 -113.1316)
		(property "Reference" "R422"
			(at 0 0 0)
			(layer "B.SilkS")
			(hide yes)
			(effects
				(font
					(size 1.27 1.27)
				)
				(justify mirror)
			)
		)
		(property "Value" "4K7R2F-GP"
			(at -0.064008 -3.993896 0)
			(unlocked yes)
			(layer "B.Fab")
			(hide yes)
			(effects
				(font
					(size 1.016 1.016)
					(thickness 0.1524)
				)
				(justify mirror)
			)
		)
		(property "Device Type" "R402H16"
			(at -0.064008 -5.517896 0)
			(unlocked yes)
			(layer "B.Fab")
			(hide yes)
			(effects
				(font
					(size 1.016 1.016)
					(thickness 0.1524)
				)
				(justify mirror)
			)
		)
		(duplicate_pad_numbers_are_jumpers no)
		(fp_line
			(start -0.508 -0.9398)
			(end 0.508 -0.9398)
			(stroke
				(width 0.1524)
				(type default)
			)
			(layer "B.SilkS")
		)
		(fp_line
			(start 0.508 -0.9398)
			(end 0.508 0.9398)
			(stroke
				(width 0.1524)
				(type default)
			)
			(layer "B.SilkS")
		)
		(fp_rect
			(start 0.508 0.9398)
			(end -0.508 -0.9398)
			(stroke
				(width 0)
				(type default)
			)
			(fill no)
			(layer "B.CrtYd")
		)
		(fp_rect
			(start 0.508 0.9398)
			(end -0.508 -0.9398)
			(stroke
				(width 0)
				(type default)
			)
			(fill no)
			(layer "B.Fab")
		)
		(pad "1" smd custom
			(at 0 -0.4445 180)
			(size 0.1397 0.1397)
			(layers "B.Cu" "B.Mask" "B.Paste")
			(net "BMC_I2C9_CLKBUF2_SCL")
			(options
				(clearance outline)
				(anchor circle)
			)
			(primitives
				(gr_poly
					(pts
						(arc
							(start -0.1778 0.2794)
							(mid -0.249642 0.249642)
							(end -0.2794 0.1778)
						)
						(arc
							(start -0.2794 -0.1778)
							(mid -0.249642 -0.249642)
							(end -0.1778 -0.2794)
						)
						(arc
							(start 0.1778 -0.2794)
							(mid 0.249642 -0.249642)
							(end 0.2794 -0.1778)
						)
						(arc
							(start 0.2794 0.1778)
							(mid 0.249642 0.249642)
							(end 0.1778 0.2794)
						)
					)
					(width 0)
					(fill yes)
				)
			)
		)
		(pad "2" smd custom
			(at 0 0.4445 180)
			(size 0.1397 0.1397)
			(layers "B.Cu" "B.Mask" "B.Paste")
			(net "P3V3_STBY")
			(options
				(clearance outline)
				(anchor circle)
			)
			(primitives
				(gr_poly
					(pts
						(arc
							(start -0.1778 0.2794)
							(mid -0.249642 0.249642)
							(end -0.2794 0.1778)
						)
						(arc
							(start -0.2794 -0.1778)
							(mid -0.249642 -0.249642)
							(end -0.1778 -0.2794)
						)
						(arc
							(start 0.1778 -0.2794)
							(mid 0.249642 -0.249642)
							(end 0.2794 -0.1778)
						)
						(arc
							(start 0.2794 0.1778)
							(mid 0.249642 0.249642)
							(end 0.1778 0.2794)
						)
					)
					(width 0)
					(fill yes)
				)
			)
		)
	)
	(footprint ""
		(layer "B.Cu")
		(at 241.0968 -48.9966 90)
		(property "Reference" "C34"
			(at 0 0 90)
			(layer "B.SilkS")
			(hide yes)
			(effects
				(font
					(size 1.27 1.27)
				)
				(justify mirror)
			)
		)
		(property "Value" "SCD1U16V1KX-1-GP"
			(at 2.8321 -1.7399 90)
			(unlocked yes)
			(layer "B.Fab")
			(hide yes)
			(effects
				(font
					(size 1.016 1.016)
					(thickness 0.1524)
				)
				(justify mirror)
			)
		)
		(property "Device Type" "C0201H13"
			(at 2.8321 -3.2639 90)
			(unlocked yes)
			(layer "B.Fab")
			(hide yes)
			(effects
				(font
					(size 1.016 1.016)
					(thickness 0.1524)
				)
				(justify mirror)
			)
		)
		(duplicate_pad_numbers_are_jumpers no)
		(fp_rect
			(start 0.2794 0.6477)
			(end -0.2794 -0.6477)
			(stroke
				(width 0)
				(type default)
			)
			(fill no)
			(layer "B.CrtYd")
		)
		(fp_rect
			(start 0.2794 0.6477)
			(end -0.2794 -0.6477)
			(stroke
				(width 0)
				(type default)
			)
			(fill no)
			(layer "B.Fab")
		)
		(pad "1" smd custom
			(at 0 -0.2794 270)
			(size 0.0762 0.0762)
			(layers "B.Cu" "B.Mask" "B.Paste")
			(net "DUT_VDD")
			(options
				(clearance outline)
				(anchor circle)
			)
			(primitives
				(gr_poly
					(pts
						(arc
							(start 0.1524 0.127)
							(mid 0.137521 0.162921)
							(end 0.1016 0.1778)
						)
						(arc
							(start -0.1016 0.1778)
							(mid -0.137521 0.162921)
							(end -0.1524 0.127)
						)
						(arc
							(start -0.1524 -0.127)
							(mid -0.137521 -0.162921)
							(end -0.1016 -0.1778)
						)
						(arc
							(start 0.1016 -0.1778)
							(mid 0.137521 -0.162921)
							(end 0.1524 -0.127)
						)
					)
					(width 0)
					(fill yes)
				)
			)
		)
		(pad "2" smd custom
			(at 0 0.2794 270)
			(size 0.0762 0.0762)
			(layers "B.Cu" "B.Mask" "B.Paste")
			(net "GND")
			(options
				(clearance outline)
				(anchor circle)
			)
			(primitives
				(gr_poly
					(pts
						(arc
							(start 0.1524 0.127)
							(mid 0.137521 0.162921)
							(end 0.1016 0.1778)
						)
						(arc
							(start -0.1016 0.1778)
							(mid -0.137521 0.162921)
							(end -0.1524 0.127)
						)
						(arc
							(start -0.1524 -0.127)
							(mid -0.137521 -0.162921)
							(end -0.1016 -0.1778)
						)
						(arc
							(start 0.1016 -0.1778)
							(mid 0.137521 -0.162921)
							(end 0.1524 -0.127)
						)
					)
					(width 0)
					(fill yes)
				)
			)
		)
	)
	(footprint ""
		(layer "B.Cu")
		(at 77.065124 -195.681092 180)
		(property "Reference" "R4112"
			(at 0 0 0)
			(layer "B.SilkS")
			(hide yes)
			(effects
				(font
					(size 1.27 1.27)
				)
				(justify mirror)
			)
		)
		(property "Value" "4K7R2F-GP"
			(at -0.064008 -3.993896 180)
			(unlocked yes)
			(layer "B.Fab")
			(hide yes)
			(effects
				(font
					(size 1.016 1.016)
					(thickness 0.1524)
				)
				(justify mirror)
			)
		)
		(property "Device Type" "R402H16"
			(at -0.064008 -5.517896 180)
			(unlocked yes)
			(layer "B.Fab")
			(hide yes)
			(effects
				(font
					(size 1.016 1.016)
					(thickness 0.1524)
				)
				(justify mirror)
			)
		)
		(duplicate_pad_numbers_are_jumpers no)
		(fp_line
			(start 0.508 -0.9398)
			(end 0.508 0.9398)
			(stroke
				(width 0.1524)
				(type default)
			)
			(layer "B.SilkS")
		)
		(fp_line
			(start -0.508 -0.9398)
			(end 0.508 -0.9398)
			(stroke
				(width 0.1524)
				(type default)
			)
			(layer "B.SilkS")
		)
		(fp_rect
			(start 0.508 0.9398)
			(end -0.508 -0.9398)
			(stroke
				(width 0)
				(type default)
			)
			(fill no)
			(layer "B.CrtYd")
		)
		(fp_rect
			(start 0.508 0.9398)
			(end -0.508 -0.9398)
			(stroke
				(width 0)
				(type default)
			)
			(fill no)
			(layer "B.Fab")
		)
		(pad "1" smd custom
			(at 0 -0.4445)
			(size 0.1397 0.1397)
			(layers "B.Cu" "B.Mask" "B.Paste")
			(net "SSD_PERST#10")
			(options
				(clearance outline)
				(anchor circle)
			)
			(primitives
				(gr_poly
					(pts
						(arc
							(start -0.1778 0.2794)
							(mid -0.249642 0.249642)
							(end -0.2794 0.1778)
						)
						(arc
							(start -0.2794 -0.1778)
							(mid -0.249642 -0.249642)
							(end -0.1778 -0.2794)
						)
						(arc
							(start 0.1778 -0.2794)
							(mid 0.249642 -0.249642)
							(end 0.2794 -0.1778)
						)
						(arc
							(start 0.2794 0.1778)
							(mid 0.249642 0.249642)
							(end 0.1778 0.2794)
						)
					)
					(width 0)
					(fill yes)
				)
			)
		)
		(pad "2" smd custom
			(at 0 0.4445)
			(size 0.1397 0.1397)
			(layers "B.Cu" "B.Mask" "B.Paste")
			(net "P3V3_STBY")
			(options
				(clearance outline)
				(anchor circle)
			)
			(primitives
				(gr_poly
					(pts
						(arc
							(start -0.1778 0.2794)
							(mid -0.249642 0.249642)
							(end -0.2794 0.1778)
						)
						(arc
							(start -0.2794 -0.1778)
							(mid -0.249642 -0.249642)
							(end -0.1778 -0.2794)
						)
						(arc
							(start 0.1778 -0.2794)
							(mid 0.249642 -0.249642)
							(end 0.2794 -0.1778)
						)
						(arc
							(start 0.2794 0.1778)
							(mid 0.249642 0.249642)
							(end 0.1778 0.2794)
						)
					)
					(width 0)
					(fill yes)
				)
			)
		)
	)
	(footprint ""
		(layer "B.Cu")
		(at 253.5936 -34.993072 90)
		(property "Reference" "C606"
			(at 0 0 90)
			(layer "B.SilkS")
			(hide yes)
			(effects
				(font
					(size 1.27 1.27)
				)
				(justify mirror)
			)
		)
		(property "Value" "SCD1U16V1KX-1-GP"
			(at 2.8321 -1.7399 90)
			(unlocked yes)
			(layer "B.Fab")
			(hide yes)
			(effects
				(font
					(size 1.016 1.016)
					(thickness 0.1524)
				)
				(justify mirror)
			)
		)
		(property "Device Type" "C0201H13"
			(at 2.8321 -3.2639 90)
			(unlocked yes)
			(layer "B.Fab")
			(hide yes)
			(effects
				(font
					(size 1.016 1.016)
					(thickness 0.1524)
				)
				(justify mirror)
			)
		)
		(duplicate_pad_numbers_are_jumpers no)
		(fp_rect
			(start 0.2794 0.6477)
			(end -0.2794 -0.6477)
			(stroke
				(width 0)
				(type default)
			)
			(fill no)
			(layer "B.CrtYd")
		)
		(fp_rect
			(start 0.2794 0.6477)
			(end -0.2794 -0.6477)
			(stroke
				(width 0)
				(type default)
			)
			(fill no)
			(layer "B.Fab")
		)
		(pad "1" smd custom
			(at 0 -0.2794 270)
			(size 0.0762 0.0762)
			(layers "B.Cu" "B.Mask" "B.Paste")
			(net "DUT_AVD_PCIE")
			(options
				(clearance outline)
				(anchor circle)
			)
			(primitives
				(gr_poly
					(pts
						(arc
							(start 0.1524 0.127)
							(mid 0.137521 0.162921)
							(end 0.1016 0.1778)
						)
						(arc
							(start -0.1016 0.1778)
							(mid -0.137521 0.162921)
							(end -0.1524 0.127)
						)
						(arc
							(start -0.1524 -0.127)
							(mid -0.137521 -0.162921)
							(end -0.1016 -0.1778)
						)
						(arc
							(start 0.1016 -0.1778)
							(mid 0.137521 -0.162921)
							(end 0.1524 -0.127)
						)
					)
					(width 0)
					(fill yes)
				)
			)
		)
		(pad "2" smd custom
			(at 0 0.2794 270)
			(size 0.0762 0.0762)
			(layers "B.Cu" "B.Mask" "B.Paste")
			(net "GND")
			(options
				(clearance outline)
				(anchor circle)
			)
			(primitives
				(gr_poly
					(pts
						(arc
							(start 0.1524 0.127)
							(mid 0.137521 0.162921)
							(end 0.1016 0.1778)
						)
						(arc
							(start -0.1016 0.1778)
							(mid -0.137521 0.162921)
							(end -0.1524 0.127)
						)
						(arc
							(start -0.1524 -0.127)
							(mid -0.137521 -0.162921)
							(end -0.1016 -0.1778)
						)
						(arc
							(start 0.1016 -0.1778)
							(mid 0.137521 -0.162921)
							(end 0.1524 -0.127)
						)
					)
					(width 0)
					(fill yes)
				)
			)
		)
	)
	(footprint ""
		(layer "B.Cu")
		(at 245.684802 -25.4)
		(property "Reference" "TP284"
			(at 0 0 0)
			(layer "B.SilkS")
			(hide yes)
			(effects
				(font
					(size 1.27 1.27)
				)
				(justify mirror)
			)
		)
		(property "Value" "TPAD28-2-GP"
			(at 0.0127 -1.6637 0)
			(unlocked yes)
			(layer "B.Fab")
			(hide yes)
			(effects
				(font
					(size 1.016 1.016)
					(thickness 0.1524)
				)
				(justify mirror)
			)
		)
		(property "Device Type" "TPAD28"
			(at 0.0127 -3.1877 0)
			(unlocked yes)
			(layer "B.Fab")
			(hide yes)
			(effects
				(font
					(size 1.016 1.016)
					(thickness 0.1524)
				)
				(justify mirror)
			)
		)
		(duplicate_pad_numbers_are_jumpers no)
		(fp_poly
			(pts
				(arc
					(start 0.3556 0)
					(mid -0.3556 0)
					(end 0.3556 0)
				)
			)
			(stroke
				(width 0)
				(type default)
			)
			(fill no)
			(layer "B.CrtYd")
		)
		(fp_poly
			(pts
				(arc
					(start 0.6096 0)
					(mid -0.6096 0)
					(end 0.6096 0)
				)
			)
			(stroke
				(width 0)
				(type default)
			)
			(fill no)
			(layer "B.Fab")
		)
		(pad "1" smd circle
			(at 0 0 180)
			(size 0.7112 0.7112)
			(layers "B.Cu" "B.Mask" "B.Paste")
			(net "TWI_SCL4")
		)
	)
)
